FILE_TYPE = CONNECTIVITY;
{Allegro Design Entry HDL 17.2-2016 S081 (4005846) 1/11/2022}
"PAGE_NUMBER" = 85;
0"NC";
1"M_A_CPU0_SB_CA<6:0>";
2"M_A_CPU0_SA_CA<6:0>";
3"M_A_CPU0_SB_CB<7:0>";
4"M_A_CPU0_SA_DQ<31:0>";
5"M_A_CPU0_SB_DQ<31:0>";
6"M_A_CPU0_SA_DQS_DP<9:0>";
7"M_A_CPU0_SB_DQS_DN<9:0>";
8"M_A_CPU0_SB_DQS_DP<9:0>";
9"M_A_CPU0_SA_CB<7:0>";
10"GND\g";
11"GND\g";
12"P3V3_STBY\g";
13"P3V3_STBY\g";
14"M_A_CPU0_SA_DQS_DN<9:0>";
15"TP_CHA_CPU0_DIMM0_RFU_4";
16"TP_CHA_CPU0_DIMM0_RFU_5";
17"TP_CHA_CPU0_DIMM0_RFU_6";
18"PWRGD_CHA_CPU0_DIMM0";
19"I3C_SPD_DDRAF_CPU0_SCL";
20"P3V3_STBY\g";
21"GND\g";
22"GND\g";
23"GND\g";
24"P12V_MEM_1\g";
25"I3C_SPD_DDRAF_CPU0_SDA";
26"TP_CHA_CPU0_DIMM0_RFU_2";
27"I3C_SPD_DDRA_CPU0_SCL";
28"M_A_CPU0_SA_RSP<0>";
29"TP_CHA_CPU0_DIMM0_RFU_0";
30"M_A_CPU0_SB_RSP<0>";
31"TP_CHA_CPU0_DIMM0_RFU_3";
32"M_A_CPU0_SB_CB<1>";
33"PD_CHA_CPU0_DIMM0_SAA";
34"M_A_CPU0_ALERT_N";
35"M_A_CPU0_RESET_N";
36"PWRGD_CHAF_CPU0";
37"M_A_CPU0_SA_CS_N<0>";
38"M_A_CPU0_SB_PAR";
39"M_A_CPU0_SB_CB<6>";
40"M_A_CPU0_SB_CB<7>";
41"M_A_CPU0_SA_CB<0>";
42"M_A_CPU0_SA_CB<1>";
43"M_A_CPU0_SA_CB<2>";
44"M_A_CPU0_SA_CB<3>";
45"M_A_CPU0_SA_CB<4>";
46"TP_CHA_CPU0_DIMM0_RFU_1";
47"M_A_CPU0_SB_DQS_DP<9>";
48"M_A_CPU0_SA_DQS_DN<6>";
49"M_A_CPU0_SA_DQS_DP<6>";
50"M_A_CPU0_SA_DQS_DN<7>";
51"M_A_CPU0_SA_DQ<14>";
52"M_A_CPU0_SA_DQ<15>";
53"M_A_CPU0_SA_DQ<20>";
54"M_A_CPU0_SA_DQ<24>";
55"M_A_CPU0_SA_DQ<25>";
56"M_A_CPU0_SA_DQ<26>";
57"M_A_CPU0_SA_DQ<27>";
58"M_A_CPU0_SA_DQ<28>";
59"M_A_CPU0_SA_DQ<29>";
60"M_A_CPU0_SA_DQS_DN<0>";
61"M_A_CPU0_SB_DQS_DN<9>";
62"M_A_CPU0_SB_DQS_DP<8>";
63"M_A_CPU0_SB_DQS_DN<8>";
64"M_A_CPU0_SB_DQS_DP<7>";
65"M_A_CPU0_SB_DQS_DN<7>";
66"M_A_CPU0_SB_DQS_DP<6>";
67"M_A_CPU0_SB_DQS_DN<6>";
68"M_A_CPU0_SB_DQS_DN<5>";
69"M_A_CPU0_SB_DQS_DP<4>";
70"M_A_CPU0_SB_DQS_DN<4>";
71"M_A_CPU0_SB_DQ<0>";
72"M_A_CPU0_SA_DQ<16>";
73"M_A_CPU0_SB_CS_N<0>";
74"M_A_CPU0_SA_CS_N<1>";
75"M_A_CPU0_SA_CA<6>";
76"M_A_CPU0_SA_CA<0>";
77"M_A_CPU0_SA_DQ<31>";
78"M_A_CPU0_SB_CA<5>";
79"M_A_CPU0_SA_DQS_DP<9>";
80"M_A_CPU0_SA_DQS_DN<9>";
81"M_A_CPU0_SA_DQ<30>";
82"M_A_CPU0_SA_DQS_DP<8>";
83"M_A_CPU0_SA_DQS_DN<8>";
84"M_A_CPU0_SA_DQS_DP<7>";
85"M_A_CPU0_SB_DQS_DP<5>";
86"M_A_CPU0_SA_DQS_DP<5>";
87"M_A_CPU0_SA_DQS_DN<5>";
88"M_A_CPU0_SA_DQS_DP<4>";
89"M_A_CPU0_SA_DQS_DN<4>";
90"M_A_CPU0_SB_DQS_DP<3>";
91"M_A_CPU0_SB_DQS_DN<3>";
92"M_A_CPU0_SA_DQS_DP<3>";
93"M_A_CPU0_SA_DQS_DN<3>";
94"M_A_CPU0_SB_DQS_DP<2>";
95"M_A_CPU0_SB_DQS_DN<2>";
96"M_A_CPU0_SA_DQS_DP<2>";
97"M_A_CPU0_SA_DQS_DN<2>";
98"M_A_CPU0_SB_DQS_DP<1>";
99"M_A_CPU0_SB_DQS_DN<1>";
100"M_A_CPU0_SA_DQS_DP<1>";
101"M_A_CPU0_SA_DQS_DN<1>";
102"M_A_CPU0_SB_DQS_DP<0>";
103"M_A_CPU0_SB_DQS_DN<0>";
104"M_A_CPU0_SA_DQS_DP<0>";
105"M_A_CPU0_SA_CA<5>";
106"M_A_CPU0_SB_CA<1>";
107"M_A_CPU0_SB_CA<4>";
108"M_A_CPU0_SA_CA<4>";
109"M_A_CPU0_SA_PAR";
110"M_A_CPU0_SB_DQ<1>";
111"M_A_CPU0_SB_DQ<2>";
112"M_A_CPU0_SB_DQ<3>";
113"M_A_CPU0_SB_DQ<4>";
114"M_A_CPU0_SB_DQ<5>";
115"M_A_CPU0_SB_DQ<6>";
116"M_A_CPU0_SB_DQ<7>";
117"M_A_CPU0_SB_DQ<8>";
118"M_A_CPU0_SB_DQ<9>";
119"M_A_CPU0_SB_DQ<10>";
120"M_A_CPU0_SB_DQ<11>";
121"M_A_CPU0_SB_DQ<12>";
122"M_A_CPU0_SB_DQ<13>";
123"M_A_CPU0_SB_DQ<14>";
124"M_A_CPU0_SB_DQ<15>";
125"M_A_CPU0_SB_DQ<16>";
126"M_A_CPU0_SB_DQ<17>";
127"M_A_CPU0_SB_DQ<18>";
128"M_A_CPU0_SB_DQ<19>";
129"M_A_CPU0_SB_DQ<20>";
130"M_A_CPU0_SB_DQ<21>";
131"M_A_CPU0_SB_DQ<22>";
132"M_A_CPU0_SB_DQ<23>";
133"M_A_CPU0_SB_DQ<24>";
134"M_A_CPU0_SB_DQ<25>";
135"M_A_CPU0_SB_DQ<26>";
136"M_A_CPU0_SB_DQ<27>";
137"M_A_CPU0_SB_DQ<28>";
138"M_A_CPU0_SB_DQ<29>";
139"M_A_CPU0_SB_DQ<30>";
140"M_A_CPU0_SB_DQ<31>";
141"M_A_CPU0_SA_DQ<0>";
142"M_A_CPU0_SA_DQ<1>";
143"M_A_CPU0_SA_DQ<2>";
144"M_A_CPU0_SA_DQ<3>";
145"M_A_CPU0_SA_DQ<4>";
146"M_A_CPU0_SA_DQ<5>";
147"M_A_CPU0_SA_DQ<6>";
148"M_A_CPU0_SA_DQ<7>";
149"M_A_CPU0_SA_DQ<8>";
150"M_A_CPU0_SA_DQ<9>";
151"M_A_CPU0_SA_DQ<10>";
152"M_A_CPU0_SA_DQ<11>";
153"M_A_CPU0_SA_DQ<12>";
154"M_A_CPU0_SA_DQ<13>";
155"M_A_CPU0_SA_DQ<17>";
156"M_A_CPU0_SA_DQ<18>";
157"M_A_CPU0_SA_DQ<19>";
158"M_A_CPU0_SA_DQ<21>";
159"M_A_CPU0_SA_DQ<22>";
160"M_A_CPU0_SA_DQ<23>";
161"M_A_CPU0_SB_CS_N<1>";
162"M_A_CPU0_CLK_DP<0>";
163"M_A_CPU0_CLK_DN<0>";
164"M_A_CPU0_SB_CB<0>";
165"M_A_CPU0_SB_CB<2>";
166"M_A_CPU0_SB_CB<3>";
167"M_A_CPU0_SB_CB<4>";
168"M_A_CPU0_SB_CB<5>";
169"M_A_CPU0_SA_CB<5>";
170"M_A_CPU0_SA_CB<6>";
171"M_A_CPU0_SB_CA<6>";
172"M_A_CPU0_SB_CA<3>";
173"M_A_CPU0_SA_CA<3>";
174"M_A_CPU0_SB_CA<2>";
175"M_A_CPU0_SA_CA<2>";
176"M_A_CPU0_SA_CA<1>";
177"M_A_CPU0_SB_CA<0>";
178"M_A_CPU0_SA_CB<7>";
179"PD_CHA_CPU0_DIMM0_SAA";
%"GND"
"1","(-650,1750)","0","mstr_symbols","I115";
;
SIZE"1B"
CDS_LIB"mstr_symbols"
BODY_TYPE"PLUMBING"
VOLTAGE"0.0"
HDL_POWER"GND";
"A\NAC"21;
%"GND"
"1","(-2250,1950)","0","mstr_symbols","I116";
;
SIZE"1B"
CDS_LIB"mstr_symbols"
BODY_TYPE"PLUMBING"
VOLTAGE"0.0"
HDL_POWER"GND";
"A\NAC"22;
%"TAP"
"1","(-7750,4025)","2","mstr_standard","I210";
;
CDS_LIB"mstr_standard"
BODY_TYPE"PLUMBING"
HDL_TAP"TRUE";
"B \NAC \NWC"9;
"S \NAC"
BN"7"178;
%"TAP"
"1","(-7750,3925)","2","mstr_standard","I211";
;
CDS_LIB"mstr_standard"
BODY_TYPE"PLUMBING"
HDL_TAP"TRUE";
"B \NAC \NWC"9;
"S \NAC"
BN"5"169;
%"TAP"
"1","(-7750,3975)","2","mstr_standard","I212";
;
CDS_LIB"mstr_standard"
BODY_TYPE"PLUMBING"
HDL_TAP"TRUE";
"B \NAC \NWC"9;
"S \NAC"
BN"6"170;
%"TAP"
"1","(-7750,3825)","2","mstr_standard","I213";
;
CDS_LIB"mstr_standard"
BODY_TYPE"PLUMBING"
HDL_TAP"TRUE";
"B \NAC \NWC"9;
"S \NAC"
BN"3"44;
%"TAP"
"1","(-7750,3875)","2","mstr_standard","I214";
;
CDS_LIB"mstr_standard"
BODY_TYPE"PLUMBING"
HDL_TAP"TRUE";
"B \NAC \NWC"9;
"S \NAC"
BN"4"45;
%"TAP"
"1","(-7750,3775)","2","mstr_standard","I215";
;
CDS_LIB"mstr_standard"
BODY_TYPE"PLUMBING"
HDL_TAP"TRUE";
"B \NAC \NWC"9;
"S \NAC"
BN"2"43;
%"TAP"
"1","(-7750,3725)","2","mstr_standard","I216";
;
CDS_LIB"mstr_standard"
BODY_TYPE"PLUMBING"
HDL_TAP"TRUE";
"B \NAC \NWC"9;
"S \NAC"
BN"1"42;
%"TAP"
"1","(-7750,3675)","2","mstr_standard","I217";
;
CDS_LIB"mstr_standard"
BODY_TYPE"PLUMBING"
HDL_TAP"TRUE";
"B \NAC \NWC"9;
"S \NAC"
BN"0"41;
%"TAP"
"1","(-7750,5375)","2","mstr_standard","I227";
;
CDS_LIB"mstr_standard"
BODY_TYPE"PLUMBING"
HDL_TAP"TRUE";
"B \NAC \NWC"2;
"S \NAC"
BN"5"105;
%"TAP"
"1","(-7750,5325)","2","mstr_standard","I228";
;
CDS_LIB"mstr_standard"
BODY_TYPE"PLUMBING"
HDL_TAP"TRUE";
"B \NAC \NWC"2;
"S \NAC"
BN"4"108;
%"TAP"
"1","(-7750,5425)","2","mstr_standard","I229";
;
CDS_LIB"mstr_standard"
BODY_TYPE"PLUMBING"
HDL_TAP"TRUE";
"B \NAC \NWC"2;
"S \NAC"
BN"6"75;
%"TAP"
"1","(-7750,5275)","2","mstr_standard","I230";
;
CDS_LIB"mstr_standard"
BODY_TYPE"PLUMBING"
HDL_TAP"TRUE";
"B \NAC \NWC"2;
"S \NAC"
BN"3"173;
%"TAP"
"1","(-7750,5225)","2","mstr_standard","I231";
;
CDS_LIB"mstr_standard"
BODY_TYPE"PLUMBING"
HDL_TAP"TRUE";
"B \NAC \NWC"2;
"S \NAC"
BN"2"175;
%"TAP"
"1","(-7750,5175)","2","mstr_standard","I232";
;
CDS_LIB"mstr_standard"
BODY_TYPE"PLUMBING"
HDL_TAP"TRUE";
"B \NAC \NWC"2;
"S \NAC"
BN"1"176;
%"TAP"
"1","(-7750,5125)","2","mstr_standard","I233";
;
CDS_LIB"mstr_standard"
BODY_TYPE"PLUMBING"
HDL_TAP"TRUE";
"B \NAC \NWC"2;
"S \NAC"
BN"0"76;
%"TAP"
"1","(-7750,5025)","2","mstr_standard","I235";
;
CDS_LIB"mstr_standard"
BODY_TYPE"PLUMBING"
HDL_TAP"TRUE";
"B \NAC \NWC"1;
"S \NAC"
BN"6"171;
%"TAP"
"1","(-7750,4975)","2","mstr_standard","I236";
;
CDS_LIB"mstr_standard"
BODY_TYPE"PLUMBING"
HDL_TAP"TRUE";
"B \NAC \NWC"1;
"S \NAC"
BN"5"78;
%"TAP"
"1","(-7750,4925)","2","mstr_standard","I237";
;
CDS_LIB"mstr_standard"
BODY_TYPE"PLUMBING"
HDL_TAP"TRUE";
"B \NAC \NWC"1;
"S \NAC"
BN"4"107;
%"TAP"
"1","(-7750,4825)","2","mstr_standard","I238";
;
CDS_LIB"mstr_standard"
BODY_TYPE"PLUMBING"
HDL_TAP"TRUE";
"B \NAC \NWC"1;
"S \NAC"
BN"2"174;
%"TAP"
"1","(-7750,4725)","2","mstr_standard","I239";
;
CDS_LIB"mstr_standard"
BODY_TYPE"PLUMBING"
HDL_TAP"TRUE";
"B \NAC \NWC"1;
"S \NAC"
BN"0"177;
%"TAP"
"1","(-7750,4775)","2","mstr_standard","I240";
;
CDS_LIB"mstr_standard"
BODY_TYPE"PLUMBING"
HDL_TAP"TRUE";
"B \NAC \NWC"1;
"S \NAC"
BN"1"106;
%"TAP"
"1","(-7750,4875)","2","mstr_standard","I241";
;
CDS_LIB"mstr_standard"
BODY_TYPE"PLUMBING"
HDL_TAP"TRUE";
"B \NAC \NWC"1;
"S \NAC"
BN"3"172;
%"TAP"
"1","(-7750,3575)","2","mstr_standard","I367";
;
CDS_LIB"mstr_standard"
BODY_TYPE"PLUMBING"
HDL_TAP"TRUE";
"B \NAC \NWC"3;
"S \NAC"
BN"7"40;
%"TAP"
"1","(-7750,3525)","2","mstr_standard","I368";
;
CDS_LIB"mstr_standard"
BODY_TYPE"PLUMBING"
HDL_TAP"TRUE";
"B \NAC \NWC"3;
"S \NAC"
BN"6"39;
%"TAP"
"1","(-7750,3475)","2","mstr_standard","I369";
;
CDS_LIB"mstr_standard"
BODY_TYPE"PLUMBING"
HDL_TAP"TRUE";
"B \NAC \NWC"3;
"S \NAC"
BN"5"168;
%"TAP"
"1","(-7750,3425)","2","mstr_standard","I370";
;
CDS_LIB"mstr_standard"
BODY_TYPE"PLUMBING"
HDL_TAP"TRUE";
"B \NAC \NWC"3;
"S \NAC"
BN"4"167;
%"TAP"
"1","(-7750,3375)","2","mstr_standard","I371";
;
CDS_LIB"mstr_standard"
BODY_TYPE"PLUMBING"
HDL_TAP"TRUE";
"B \NAC \NWC"3;
"S \NAC"
BN"3"166;
%"TAP"
"1","(-7750,3225)","2","mstr_standard","I372";
;
CDS_LIB"mstr_standard"
BODY_TYPE"PLUMBING"
HDL_TAP"TRUE";
"B \NAC \NWC"3;
"S \NAC"
BN"0"164;
%"TAP"
"1","(-7750,3275)","2","mstr_standard","I373";
;
CDS_LIB"mstr_standard"
BODY_TYPE"PLUMBING"
HDL_TAP"TRUE";
"B \NAC \NWC"3;
"S \NAC"
BN"1"32;
%"TAP"
"1","(-7750,3325)","2","mstr_standard","I374";
;
CDS_LIB"mstr_standard"
BODY_TYPE"PLUMBING"
HDL_TAP"TRUE";
"B \NAC \NWC"3;
"S \NAC"
BN"2"165;
%"TAP"
"1","(-6050,2275)","0","mstr_standard","I383";
;
CDS_LIB"mstr_standard"
BODY_TYPE"PLUMBING"
HDL_TAP"TRUE";
"B \NAC \NWC"5;
"S \NAC"
BN"1"110;
%"TAP"
"1","(-6050,2225)","0","mstr_standard","I384";
;
CDS_LIB"mstr_standard"
BODY_TYPE"PLUMBING"
HDL_TAP"TRUE";
"B \NAC \NWC"5;
"S \NAC"
BN"0"71;
%"TAP"
"1","(-6050,2325)","0","mstr_standard","I385";
;
CDS_LIB"mstr_standard"
BODY_TYPE"PLUMBING"
HDL_TAP"TRUE";
"B \NAC \NWC"5;
"S \NAC"
BN"2"111;
%"TAP"
"1","(-6050,2375)","0","mstr_standard","I386";
;
CDS_LIB"mstr_standard"
BODY_TYPE"PLUMBING"
HDL_TAP"TRUE";
"B \NAC \NWC"5;
"S \NAC"
BN"3"112;
%"TAP"
"1","(-6050,2425)","0","mstr_standard","I387";
;
CDS_LIB"mstr_standard"
BODY_TYPE"PLUMBING"
HDL_TAP"TRUE";
"B \NAC \NWC"5;
"S \NAC"
BN"4"113;
%"TAP"
"1","(-6050,2475)","0","mstr_standard","I388";
;
CDS_LIB"mstr_standard"
BODY_TYPE"PLUMBING"
HDL_TAP"TRUE";
"B \NAC \NWC"5;
"S \NAC"
BN"5"114;
%"TAP"
"1","(-6050,2525)","0","mstr_standard","I389";
;
CDS_LIB"mstr_standard"
BODY_TYPE"PLUMBING"
HDL_TAP"TRUE";
"B \NAC \NWC"5;
"S \NAC"
BN"6"115;
%"TAP"
"1","(-6050,2575)","0","mstr_standard","I390";
;
CDS_LIB"mstr_standard"
BODY_TYPE"PLUMBING"
HDL_TAP"TRUE";
"B \NAC \NWC"5;
"S \NAC"
BN"7"116;
%"TAP"
"1","(-6050,2625)","0","mstr_standard","I391";
;
CDS_LIB"mstr_standard"
BODY_TYPE"PLUMBING"
HDL_TAP"TRUE";
"B \NAC \NWC"5;
"S \NAC"
BN"8"117;
%"TAP"
"1","(-6050,2675)","0","mstr_standard","I392";
;
CDS_LIB"mstr_standard"
BODY_TYPE"PLUMBING"
HDL_TAP"TRUE";
"B \NAC \NWC"5;
"S \NAC"
BN"9"118;
%"TAP"
"1","(-6050,2725)","0","mstr_standard","I393";
;
CDS_LIB"mstr_standard"
BODY_TYPE"PLUMBING"
HDL_TAP"TRUE";
"B \NAC \NWC"5;
"S \NAC"
BN"10"119;
%"TAP"
"1","(-6050,2825)","0","mstr_standard","I394";
;
CDS_LIB"mstr_standard"
BODY_TYPE"PLUMBING"
HDL_TAP"TRUE";
"B \NAC \NWC"5;
"S \NAC"
BN"12"121;
%"TAP"
"1","(-6050,2775)","0","mstr_standard","I395";
;
CDS_LIB"mstr_standard"
BODY_TYPE"PLUMBING"
HDL_TAP"TRUE";
"B \NAC \NWC"5;
"S \NAC"
BN"11"120;
%"TAP"
"1","(-6050,2875)","0","mstr_standard","I396";
;
CDS_LIB"mstr_standard"
BODY_TYPE"PLUMBING"
HDL_TAP"TRUE";
"B \NAC \NWC"5;
"S \NAC"
BN"13"122;
%"TAP"
"1","(-6050,2975)","0","mstr_standard","I397";
;
CDS_LIB"mstr_standard"
BODY_TYPE"PLUMBING"
HDL_TAP"TRUE";
"B \NAC \NWC"5;
"S \NAC"
BN"15"124;
%"TAP"
"1","(-6050,2925)","0","mstr_standard","I398";
;
CDS_LIB"mstr_standard"
BODY_TYPE"PLUMBING"
HDL_TAP"TRUE";
"B \NAC \NWC"5;
"S \NAC"
BN"14"123;
%"TAP"
"1","(-6050,3025)","0","mstr_standard","I399";
;
CDS_LIB"mstr_standard"
BODY_TYPE"PLUMBING"
HDL_TAP"TRUE";
"B \NAC \NWC"5;
"S \NAC"
BN"16"125;
%"TAP"
"1","(-6050,3075)","0","mstr_standard","I400";
;
CDS_LIB"mstr_standard"
BODY_TYPE"PLUMBING"
HDL_TAP"TRUE";
"B \NAC \NWC"5;
"S \NAC"
BN"17"126;
%"TAP"
"1","(-6050,3125)","0","mstr_standard","I401";
;
CDS_LIB"mstr_standard"
BODY_TYPE"PLUMBING"
HDL_TAP"TRUE";
"B \NAC \NWC"5;
"S \NAC"
BN"18"127;
%"TAP"
"1","(-6050,3175)","0","mstr_standard","I402";
;
CDS_LIB"mstr_standard"
BODY_TYPE"PLUMBING"
HDL_TAP"TRUE";
"B \NAC \NWC"5;
"S \NAC"
BN"19"128;
%"TAP"
"1","(-6050,3375)","0","mstr_standard","I403";
;
CDS_LIB"mstr_standard"
BODY_TYPE"PLUMBING"
HDL_TAP"TRUE";
"B \NAC \NWC"5;
"S \NAC"
BN"23"132;
%"TAP"
"1","(-6050,3225)","0","mstr_standard","I404";
;
CDS_LIB"mstr_standard"
BODY_TYPE"PLUMBING"
HDL_TAP"TRUE";
"B \NAC \NWC"5;
"S \NAC"
BN"20"129;
%"TAP"
"1","(-6050,3275)","0","mstr_standard","I405";
;
CDS_LIB"mstr_standard"
BODY_TYPE"PLUMBING"
HDL_TAP"TRUE";
"B \NAC \NWC"5;
"S \NAC"
BN"21"130;
%"TAP"
"1","(-6050,3325)","0","mstr_standard","I406";
;
CDS_LIB"mstr_standard"
BODY_TYPE"PLUMBING"
HDL_TAP"TRUE";
"B \NAC \NWC"5;
"S \NAC"
BN"22"131;
%"TAP"
"1","(-6050,3425)","0","mstr_standard","I407";
;
CDS_LIB"mstr_standard"
BODY_TYPE"PLUMBING"
HDL_TAP"TRUE";
"B \NAC \NWC"5;
"S \NAC"
BN"24"133;
%"TAP"
"1","(-6050,3625)","0","mstr_standard","I408";
;
CDS_LIB"mstr_standard"
BODY_TYPE"PLUMBING"
HDL_TAP"TRUE";
"B \NAC \NWC"5;
"S \NAC"
BN"28"137;
%"TAP"
"1","(-6050,3475)","0","mstr_standard","I409";
;
CDS_LIB"mstr_standard"
BODY_TYPE"PLUMBING"
HDL_TAP"TRUE";
"B \NAC \NWC"5;
"S \NAC"
BN"25"134;
%"TAP"
"1","(-6050,3525)","0","mstr_standard","I410";
;
CDS_LIB"mstr_standard"
BODY_TYPE"PLUMBING"
HDL_TAP"TRUE";
"B \NAC \NWC"5;
"S \NAC"
BN"26"135;
%"TAP"
"1","(-6050,3575)","0","mstr_standard","I411";
;
CDS_LIB"mstr_standard"
BODY_TYPE"PLUMBING"
HDL_TAP"TRUE";
"B \NAC \NWC"5;
"S \NAC"
BN"27"136;
%"TAP"
"1","(-6050,3675)","0","mstr_standard","I412";
;
CDS_LIB"mstr_standard"
BODY_TYPE"PLUMBING"
HDL_TAP"TRUE";
"B \NAC \NWC"5;
"S \NAC"
BN"29"138;
%"TAP"
"1","(-6050,3875)","0","mstr_standard","I413";
;
CDS_LIB"mstr_standard"
BODY_TYPE"PLUMBING"
HDL_TAP"TRUE";
"B \NAC \NWC"4;
"S \NAC"
BN"0"141;
%"TAP"
"1","(-6050,3725)","0","mstr_standard","I414";
;
CDS_LIB"mstr_standard"
BODY_TYPE"PLUMBING"
HDL_TAP"TRUE";
"B \NAC \NWC"5;
"S \NAC"
BN"30"139;
%"TAP"
"1","(-6050,3775)","0","mstr_standard","I415";
;
CDS_LIB"mstr_standard"
BODY_TYPE"PLUMBING"
HDL_TAP"TRUE";
"B \NAC \NWC"5;
"S \NAC"
BN"31"140;
%"TAP"
"1","(-6050,3975)","0","mstr_standard","I416";
;
CDS_LIB"mstr_standard"
BODY_TYPE"PLUMBING"
HDL_TAP"TRUE";
"B \NAC \NWC"4;
"S \NAC"
BN"2"143;
%"TAP"
"1","(-6050,3925)","0","mstr_standard","I417";
;
CDS_LIB"mstr_standard"
BODY_TYPE"PLUMBING"
HDL_TAP"TRUE";
"B \NAC \NWC"4;
"S \NAC"
BN"1"142;
%"TAP"
"1","(-6050,4025)","0","mstr_standard","I418";
;
CDS_LIB"mstr_standard"
BODY_TYPE"PLUMBING"
HDL_TAP"TRUE";
"B \NAC \NWC"4;
"S \NAC"
BN"3"144;
%"TAP"
"1","(-6050,4125)","0","mstr_standard","I419";
;
CDS_LIB"mstr_standard"
BODY_TYPE"PLUMBING"
HDL_TAP"TRUE";
"B \NAC \NWC"4;
"S \NAC"
BN"5"146;
%"TAP"
"1","(-6050,4075)","0","mstr_standard","I420";
;
CDS_LIB"mstr_standard"
BODY_TYPE"PLUMBING"
HDL_TAP"TRUE";
"B \NAC \NWC"4;
"S \NAC"
BN"4"145;
%"TAP"
"1","(-6050,4225)","0","mstr_standard","I421";
;
CDS_LIB"mstr_standard"
BODY_TYPE"PLUMBING"
HDL_TAP"TRUE";
"B \NAC \NWC"4;
"S \NAC"
BN"7"148;
%"TAP"
"1","(-6050,4175)","0","mstr_standard","I422";
;
CDS_LIB"mstr_standard"
BODY_TYPE"PLUMBING"
HDL_TAP"TRUE";
"B \NAC \NWC"4;
"S \NAC"
BN"6"147;
%"TAP"
"1","(-6050,4275)","0","mstr_standard","I423";
;
CDS_LIB"mstr_standard"
BODY_TYPE"PLUMBING"
HDL_TAP"TRUE";
"B \NAC \NWC"4;
"S \NAC"
BN"8"149;
%"TAP"
"1","(-6050,4375)","0","mstr_standard","I424";
;
CDS_LIB"mstr_standard"
BODY_TYPE"PLUMBING"
HDL_TAP"TRUE";
"B \NAC \NWC"4;
"S \NAC"
BN"10"151;
%"TAP"
"1","(-6050,4325)","0","mstr_standard","I425";
;
CDS_LIB"mstr_standard"
BODY_TYPE"PLUMBING"
HDL_TAP"TRUE";
"B \NAC \NWC"4;
"S \NAC"
BN"9"150;
%"TAP"
"1","(-6050,4425)","0","mstr_standard","I426";
;
CDS_LIB"mstr_standard"
BODY_TYPE"PLUMBING"
HDL_TAP"TRUE";
"B \NAC \NWC"4;
"S \NAC"
BN"11"152;
%"TAP"
"1","(-6050,4475)","0","mstr_standard","I427";
;
CDS_LIB"mstr_standard"
BODY_TYPE"PLUMBING"
HDL_TAP"TRUE";
"B \NAC \NWC"4;
"S \NAC"
BN"12"153;
%"TAP"
"1","(-6050,4525)","0","mstr_standard","I428";
;
CDS_LIB"mstr_standard"
BODY_TYPE"PLUMBING"
HDL_TAP"TRUE";
"B \NAC \NWC"4;
"S \NAC"
BN"13"154;
%"TAP"
"1","(-6050,4575)","0","mstr_standard","I429";
;
CDS_LIB"mstr_standard"
BODY_TYPE"PLUMBING"
HDL_TAP"TRUE";
"B \NAC \NWC"4;
"S \NAC"
BN"14"51;
%"TAP"
"1","(-6050,4625)","0","mstr_standard","I430";
;
CDS_LIB"mstr_standard"
BODY_TYPE"PLUMBING"
HDL_TAP"TRUE";
"B \NAC \NWC"4;
"S \NAC"
BN"15"52;
%"TAP"
"1","(-6050,4825)","0","mstr_standard","I431";
;
CDS_LIB"mstr_standard"
BODY_TYPE"PLUMBING"
HDL_TAP"TRUE";
"B \NAC \NWC"4;
"S \NAC"
BN"19"157;
%"TAP"
"1","(-6050,4875)","0","mstr_standard","I432";
;
CDS_LIB"mstr_standard"
BODY_TYPE"PLUMBING"
HDL_TAP"TRUE";
"B \NAC \NWC"4;
"S \NAC"
BN"20"53;
%"TAP"
"1","(-6050,4675)","0","mstr_standard","I433";
;
CDS_LIB"mstr_standard"
BODY_TYPE"PLUMBING"
HDL_TAP"TRUE";
"B \NAC \NWC"4;
"S \NAC"
BN"16"72;
%"TAP"
"1","(-6050,4725)","0","mstr_standard","I434";
;
CDS_LIB"mstr_standard"
BODY_TYPE"PLUMBING"
HDL_TAP"TRUE";
"B \NAC \NWC"4;
"S \NAC"
BN"17"155;
%"TAP"
"1","(-6050,4775)","0","mstr_standard","I435";
;
CDS_LIB"mstr_standard"
BODY_TYPE"PLUMBING"
HDL_TAP"TRUE";
"B \NAC \NWC"4;
"S \NAC"
BN"18"156;
%"TAP"
"1","(-6050,5025)","0","mstr_standard","I437";
;
CDS_LIB"mstr_standard"
BODY_TYPE"PLUMBING"
HDL_TAP"TRUE";
"B \NAC \NWC"4;
"S \NAC"
BN"23"160;
%"TAP"
"1","(-6050,4925)","0","mstr_standard","I438";
;
CDS_LIB"mstr_standard"
BODY_TYPE"PLUMBING"
HDL_TAP"TRUE";
"B \NAC \NWC"4;
"S \NAC"
BN"21"158;
%"TAP"
"1","(-6050,4975)","0","mstr_standard","I439";
;
CDS_LIB"mstr_standard"
BODY_TYPE"PLUMBING"
HDL_TAP"TRUE";
"B \NAC \NWC"4;
"S \NAC"
BN"22"159;
%"TAP"
"1","(-6050,5175)","0","mstr_standard","I440";
;
CDS_LIB"mstr_standard"
BODY_TYPE"PLUMBING"
HDL_TAP"TRUE";
"B \NAC \NWC"4;
"S \NAC"
BN"26"56;
%"TAP"
"1","(-6050,5125)","0","mstr_standard","I441";
;
CDS_LIB"mstr_standard"
BODY_TYPE"PLUMBING"
HDL_TAP"TRUE";
"B \NAC \NWC"4;
"S \NAC"
BN"25"55;
%"TAP"
"1","(-6050,5075)","0","mstr_standard","I442";
;
CDS_LIB"mstr_standard"
BODY_TYPE"PLUMBING"
HDL_TAP"TRUE";
"B \NAC \NWC"4;
"S \NAC"
BN"24"54;
%"TAP"
"1","(-6050,5325)","0","mstr_standard","I443";
;
CDS_LIB"mstr_standard"
BODY_TYPE"PLUMBING"
HDL_TAP"TRUE";
"B \NAC \NWC"4;
"S \NAC"
BN"29"59;
%"TAP"
"1","(-6050,5375)","0","mstr_standard","I444";
;
CDS_LIB"mstr_standard"
BODY_TYPE"PLUMBING"
HDL_TAP"TRUE";
"B \NAC \NWC"4;
"S \NAC"
BN"30"81;
%"TAP"
"1","(-6050,5425)","0","mstr_standard","I445";
;
CDS_LIB"mstr_standard"
BODY_TYPE"PLUMBING"
HDL_TAP"TRUE";
"B \NAC \NWC"4;
"S \NAC"
BN"31"77;
%"TAP"
"1","(-6050,5225)","0","mstr_standard","I446";
;
CDS_LIB"mstr_standard"
BODY_TYPE"PLUMBING"
HDL_TAP"TRUE";
"B \NAC \NWC"4;
"S \NAC"
BN"27"57;
%"TAP"
"1","(-6050,5275)","0","mstr_standard","I447";
;
CDS_LIB"mstr_standard"
BODY_TYPE"PLUMBING"
HDL_TAP"TRUE";
"B \NAC \NWC"4;
"S \NAC"
BN"28"58;
%"TAP"
"1","(-3600,3425)","0","mstr_standard","I449";
;
CDS_LIB"mstr_standard"
BODY_TYPE"PLUMBING"
HDL_TAP"TRUE";
"B \NAC \NWC"8;
"S \NAC"
BN"0"102;
%"TAP"
"1","(-3600,3525)","0","mstr_standard","I450";
;
CDS_LIB"mstr_standard"
BODY_TYPE"PLUMBING"
HDL_TAP"TRUE";
"B \NAC \NWC"8;
"S \NAC"
BN"1"98;
%"TAP"
"1","(-3400,3575)","0","mstr_standard","I451";
;
CDS_LIB"mstr_standard"
BODY_TYPE"PLUMBING"
HDL_TAP"TRUE";
"B \NAC \NWC"7;
"S \NAC"
BN"2"95;
%"TAP"
"1","(-3400,3475)","0","mstr_standard","I452";
;
CDS_LIB"mstr_standard"
BODY_TYPE"PLUMBING"
HDL_TAP"TRUE";
"B \NAC \NWC"7;
"S \NAC"
BN"1"99;
%"TAP"
"1","(-3400,3375)","0","mstr_standard","I453";
;
CDS_LIB"mstr_standard"
BODY_TYPE"PLUMBING"
HDL_TAP"TRUE";
"B \NAC \NWC"7;
"S \NAC"
BN"0"103;
%"TAP"
"1","(-3600,3625)","0","mstr_standard","I454";
;
CDS_LIB"mstr_standard"
BODY_TYPE"PLUMBING"
HDL_TAP"TRUE";
"B \NAC \NWC"8;
"S \NAC"
BN"2"94;
%"TAP"
"1","(-3600,3725)","0","mstr_standard","I455";
;
CDS_LIB"mstr_standard"
BODY_TYPE"PLUMBING"
HDL_TAP"TRUE";
"B \NAC \NWC"8;
"S \NAC"
BN"3"90;
%"TAP"
"1","(-3600,3825)","0","mstr_standard","I456";
;
CDS_LIB"mstr_standard"
BODY_TYPE"PLUMBING"
HDL_TAP"TRUE";
"B \NAC \NWC"8;
"S \NAC"
BN"4"69;
%"TAP"
"1","(-3400,3675)","0","mstr_standard","I457";
;
CDS_LIB"mstr_standard"
BODY_TYPE"PLUMBING"
HDL_TAP"TRUE";
"B \NAC \NWC"7;
"S \NAC"
BN"3"91;
%"TAP"
"1","(-3400,3775)","0","mstr_standard","I458";
;
CDS_LIB"mstr_standard"
BODY_TYPE"PLUMBING"
HDL_TAP"TRUE";
"B \NAC \NWC"7;
"S \NAC"
BN"4"70;
%"TAP"
"1","(-3600,3925)","0","mstr_standard","I459";
;
CDS_LIB"mstr_standard"
BODY_TYPE"PLUMBING"
HDL_TAP"TRUE";
"B \NAC \NWC"8;
"S \NAC"
BN"5"85;
%"TAP"
"1","(-3600,4025)","0","mstr_standard","I460";
;
CDS_LIB"mstr_standard"
BODY_TYPE"PLUMBING"
HDL_TAP"TRUE";
"B \NAC \NWC"8;
"S \NAC"
BN"6"66;
%"TAP"
"1","(-3400,4075)","0","mstr_standard","I461";
;
CDS_LIB"mstr_standard"
BODY_TYPE"PLUMBING"
HDL_TAP"TRUE";
"B \NAC \NWC"7;
"S \NAC"
BN"7"65;
%"TAP"
"1","(-3400,3975)","0","mstr_standard","I462";
;
CDS_LIB"mstr_standard"
BODY_TYPE"PLUMBING"
HDL_TAP"TRUE";
"B \NAC \NWC"7;
"S \NAC"
BN"6"67;
%"TAP"
"1","(-3400,3875)","0","mstr_standard","I463";
;
CDS_LIB"mstr_standard"
BODY_TYPE"PLUMBING"
HDL_TAP"TRUE";
"B \NAC \NWC"7;
"S \NAC"
BN"5"68;
%"TAP"
"1","(-3600,4125)","0","mstr_standard","I464";
;
CDS_LIB"mstr_standard"
BODY_TYPE"PLUMBING"
HDL_TAP"TRUE";
"B \NAC \NWC"8;
"S \NAC"
BN"7"64;
%"TAP"
"1","(-3600,4225)","0","mstr_standard","I465";
;
CDS_LIB"mstr_standard"
BODY_TYPE"PLUMBING"
HDL_TAP"TRUE";
"B \NAC \NWC"8;
"S \NAC"
BN"8"62;
%"TAP"
"1","(-3600,4325)","0","mstr_standard","I466";
;
CDS_LIB"mstr_standard"
BODY_TYPE"PLUMBING"
HDL_TAP"TRUE";
"B \NAC \NWC"8;
"S \NAC"
BN"9"47;
%"TAP"
"1","(-3400,4175)","0","mstr_standard","I467";
;
CDS_LIB"mstr_standard"
BODY_TYPE"PLUMBING"
HDL_TAP"TRUE";
"B \NAC \NWC"7;
"S \NAC"
BN"8"63;
%"TAP"
"1","(-3400,4275)","0","mstr_standard","I468";
;
CDS_LIB"mstr_standard"
BODY_TYPE"PLUMBING"
HDL_TAP"TRUE";
"B \NAC \NWC"7;
"S \NAC"
BN"9"61;
%"TAP"
"1","(-3600,4475)","0","mstr_standard","I469";
;
CDS_LIB"mstr_standard"
BODY_TYPE"PLUMBING"
HDL_TAP"TRUE";
"B \NAC \NWC"6;
"S \NAC"
BN"0"104;
%"TAP"
"1","(-3600,4575)","0","mstr_standard","I470";
;
CDS_LIB"mstr_standard"
BODY_TYPE"PLUMBING"
HDL_TAP"TRUE";
"B \NAC \NWC"6;
"S \NAC"
BN"1"100;
%"TAP"
"1","(-3400,4425)","0","mstr_standard","I471";
;
CDS_LIB"mstr_standard"
BODY_TYPE"PLUMBING"
HDL_TAP"TRUE";
"B \NAC \NWC"14;
"S \NAC"
BN"0"60;
%"TAP"
"1","(-3400,4525)","0","mstr_standard","I472";
;
CDS_LIB"mstr_standard"
BODY_TYPE"PLUMBING"
HDL_TAP"TRUE";
"B \NAC \NWC"14;
"S \NAC"
BN"1"101;
%"TAP"
"1","(-3600,4675)","0","mstr_standard","I473";
;
CDS_LIB"mstr_standard"
BODY_TYPE"PLUMBING"
HDL_TAP"TRUE";
"B \NAC \NWC"6;
"S \NAC"
BN"2"96;
%"TAP"
"1","(-3600,4775)","0","mstr_standard","I474";
;
CDS_LIB"mstr_standard"
BODY_TYPE"PLUMBING"
HDL_TAP"TRUE";
"B \NAC \NWC"6;
"S \NAC"
BN"3"92;
%"TAP"
"1","(-3400,4625)","0","mstr_standard","I475";
;
CDS_LIB"mstr_standard"
BODY_TYPE"PLUMBING"
HDL_TAP"TRUE";
"B \NAC \NWC"14;
"S \NAC"
BN"2"97;
%"TAP"
"1","(-3400,4725)","0","mstr_standard","I476";
;
CDS_LIB"mstr_standard"
BODY_TYPE"PLUMBING"
HDL_TAP"TRUE";
"B \NAC \NWC"14;
"S \NAC"
BN"3"93;
%"TAP"
"1","(-3400,4825)","0","mstr_standard","I477";
;
CDS_LIB"mstr_standard"
BODY_TYPE"PLUMBING"
HDL_TAP"TRUE";
"B \NAC \NWC"14;
"S \NAC"
BN"4"89;
%"TAP"
"1","(-3600,4875)","0","mstr_standard","I480";
;
CDS_LIB"mstr_standard"
BODY_TYPE"PLUMBING"
HDL_TAP"TRUE";
"B \NAC \NWC"6;
"S \NAC"
BN"4"88;
%"TAP"
"1","(-3600,4975)","0","mstr_standard","I481";
;
CDS_LIB"mstr_standard"
BODY_TYPE"PLUMBING"
HDL_TAP"TRUE";
"B \NAC \NWC"6;
"S \NAC"
BN"5"86;
%"TAP"
"1","(-3600,5075)","0","mstr_standard","I482";
;
CDS_LIB"mstr_standard"
BODY_TYPE"PLUMBING"
HDL_TAP"TRUE";
"B \NAC \NWC"6;
"S \NAC"
BN"6"49;
%"TAP"
"1","(-3400,5125)","0","mstr_standard","I483";
;
CDS_LIB"mstr_standard"
BODY_TYPE"PLUMBING"
HDL_TAP"TRUE";
"B \NAC \NWC"14;
"S \NAC"
BN"7"50;
%"TAP"
"1","(-3400,5025)","0","mstr_standard","I484";
;
CDS_LIB"mstr_standard"
BODY_TYPE"PLUMBING"
HDL_TAP"TRUE";
"B \NAC \NWC"14;
"S \NAC"
BN"6"48;
%"TAP"
"1","(-3400,4925)","0","mstr_standard","I485";
;
CDS_LIB"mstr_standard"
BODY_TYPE"PLUMBING"
HDL_TAP"TRUE";
"B \NAC \NWC"14;
"S \NAC"
BN"5"87;
%"TAP"
"1","(-3600,5175)","0","mstr_standard","I486";
;
CDS_LIB"mstr_standard"
BODY_TYPE"PLUMBING"
HDL_TAP"TRUE";
"B \NAC \NWC"6;
"S \NAC"
BN"7"84;
%"TAP"
"1","(-3600,5275)","0","mstr_standard","I487";
;
CDS_LIB"mstr_standard"
BODY_TYPE"PLUMBING"
HDL_TAP"TRUE";
"B \NAC \NWC"6;
"S \NAC"
BN"8"82;
%"TAP"
"1","(-3600,5375)","0","mstr_standard","I488";
;
CDS_LIB"mstr_standard"
BODY_TYPE"PLUMBING"
HDL_TAP"TRUE";
"B \NAC \NWC"6;
"S \NAC"
BN"9"79;
%"TAP"
"1","(-3400,5325)","0","mstr_standard","I489";
;
CDS_LIB"mstr_standard"
BODY_TYPE"PLUMBING"
HDL_TAP"TRUE";
"B \NAC \NWC"14;
"S \NAC"
BN"9"80;
%"TAP"
"1","(-3400,5225)","0","mstr_standard","I490";
;
CDS_LIB"mstr_standard"
BODY_TYPE"PLUMBING"
HDL_TAP"TRUE";
"B \NAC \NWC"14;
"S \NAC"
BN"8"83;
%"VCC_CORE"
"1","(-8875,3525)","0","mstr_symbols","I493";
;
HDL_POWER"P3V3_STBY"
CDS_LIB"mstr_symbols"
VOLTAGE"3.3"
ROOM"PVCCINFAON_CPU0_CTRL";
"A"20;
%"GND"
"1","(-6500,1100)","0","mstr_symbols","I498";
;
BOM_COST"MEM"
CDS_LIB"mstr_symbols"
SIZE"1B"
BODY_TYPE"PLUMBING"
VOLTAGE"0.0"
HDL_POWER"GND";
"A\NAC"10;
%"Q_RES"
"2","(-6500,1325)","0","pure_quanta","I499";
;
LOCATION"R7"
SEC"1"
WATTAGE"1/16W"
MATERIAL"CHIP"
TOLERANCE"1%"
VALUE"10K"
PART_NUMBER"CS31002FB08"
PACK_TYPE"0402LF"
CDS_LIB"pure_quanta"
SEC_TYPE"0402LF"
BOM_COST"MEM"
ROOM"MEM_CH_A_CPU0_DIMM1";
"A"
$PN"1"
XNET_PINS"3"179;
"B"
$PN"2"
XNET_PINS"2"10;
%"Q_CAP"
"1","(-2950,6050)","2","pure_quanta","I519";
;
LOCATION"C89"
$SEC"1"
CDS_SEC"1"
MATERIAL"X6S"
TOLERANCE"10%"
VALUE"10UF"
VOLTAGE"25V"
PACK_TYPE"C0805"
PART_NUMBER"CH6104KEA00"
CDS_LIB"pure_quanta"
BOM_COST"MEM"
ROOM"MEM_CH_A_CPU0_DIMM1";
"B"
$PN"2"23;
"A"
$PN"1"24;
%"GND"
"1","(-2950,5700)","0","mstr_symbols","I522";
;
BOM_COST"MEM"
SIZE"1B"
CDS_LIB"mstr_symbols"
BODY_TYPE"PLUMBING"
VOLTAGE"0"
ROOM"MEM_EFGH_DECOUPLING_CAPS"
HDL_POWER"GND";
"A\NAC"23;
%"Q_CAP"
"1","(-9000,3225)","2","pure_quanta","I523";
;
LOCATION"C88"
$SEC"1"
CDS_SEC"1"
VOLTAGE"25V"
MATERIAL"X7R"
TOLERANCE"10%"
VALUE"0.1UF"
PACK_TYPE"0402"
PART_NUMBER"CH4104K1B00"
BOM_COST"MEM"
CDS_LIB"pure_quanta"
ROOM"MEM_CH_A_CPU0_DIMM1";
"B"
$PN"2"11;
"A"
$PN"1"20;
%"GND"
"1","(-9000,3000)","0","mstr_symbols","I524";
;
BOM_COST"MEM"
SIZE"1B"
CDS_LIB"mstr_symbols"
BODY_TYPE"PLUMBING"
VOLTAGE"0"
ROOM"MEM_EFGH_DECOUPLING_CAPS"
HDL_POWER"GND";
"A\NAC"11;
%"Q_RES"
"1","(-8575,2250)","2","pure_quanta","I525";
;
LOCATION"R291"
$SEC"1"
CDS_SEC"1"
VALUE"0"
BOM_COST"MEM"
CDS_LIB"pure_quanta"
WATTAGE"1/16W"
MATERIAL"CHIP"
TOLERANCE"5%"
PART_NUMBER"CS00002JB38"
PACK_TYPE"0402LF"
ROOM"RST_CPU0_PLD_TO_DIMM";
"B"
$PN"2"36;
"A"
$PN"1"18;
%"Q_RES"
"2","(-8700,2400)","2","pure_quanta","I526";
;
LOCATION"R88"
$SEC"1"
CDS_SEC"1"
PACK_TYPE"0402LF"
WATTAGE"1/16W"
PART_NUMBER"TMP_QCS21002JB34"
MATERIAL"CHIP"
TOLERANCE"5%"
VALUE"1K"
CDS_LIB"pure_quanta"
BOM_COST"MEM"
ROOM"MEM_CH_A_CPU0_DIMM1";
"A"
$PN"1"12;
"B"
$PN"2"36;
%"VCC_CORE"
"1","(-8700,2575)","0","mstr_symbols","I527";
;
HDL_POWER"P3V3_STBY"
CDS_LIB"mstr_symbols"
VOLTAGE"3.3"
ROOM"PVCCINFAON_CPU0_CTRL";
"A"12;
%"Q_RES"
"2","(-8450,2400)","0","pure_quanta","I528";
;
LOCATION"R89"
$SEC"1"
CDS_SEC"1"
WATTAGE"1/16W"
MATERIAL"EMPTY"
VALUE"1K"
TOLERANCE"5%"
PACK_TYPE"0402LF"
CDS_LIB"pure_quanta"
BOM_COST"MEM"
PART_NUMBER"TMP_QCS21002JB34"
ROOM"MEM_CH_A_CPU0_DIMM1";
"A"
$PN"1"13;
"B"
$PN"2"18;
%"VCC_CORE"
"1","(-8450,2575)","0","mstr_symbols","I529";
;
HDL_POWER"P3V3_STBY"
CDS_LIB"mstr_symbols"
VOLTAGE"3.3"
ROOM"PVCCINFAON_CPU0_CTRL";
"A"13;
%"Q_CAP"
"1","(-2375,6050)","2","pure_quanta","I534";
;
LOCATION"C142"
$SEC"1"
CDS_SEC"1"
MATERIAL"X6S"
TOLERANCE"10%"
VALUE"10UF"
PART_NUMBER"CH6104KEA00"
VOLTAGE"25V"
PACK_TYPE"C0805"
CDS_LIB"pure_quanta"
BOM_COST"MEM"
ROOM"MEM_CH_A_CPU0_DIMM1";
"B"
$PN"2"23;
"A"
$PN"1"24;
%"UNIVERSAL_POWER"
"1","(-2950,6375)","0","pure_quanta_power","I535";
;
HDL_POWER"P12V_MEM_1"
BOM_COST"VR_SYSTEM"
CDS_LIB"pure_quanta_power";
"A"24;
%"SCONN288_DDR506112002KQ"
"1","(-6900,3675)","0","pure_quanta","I536";
;
LOCATION"J1"
$SEC"1"
CDS_SEC"1"
MATERIAL"IO"
PART_TYPE"SMLF"
VALUE"SCONN288_DDR506112002KQ"
PART_NUMBER"DFHST8FS479"
NEEDS_NO_SIZE"TRUE"
CDS_LMAN_SYM_OUTLINE"-450,1900,450,-1850"
CDS_LIB"pure_quanta";
"PWR_GOOD||FAIL_N"
$PN"147"18;
"DQ31_A"
$PN"194"77;
"CB7_A"
$PN"205"178;
"CB4_A"
$PN"58"45;
"CB1_A"
$PN"53"42;
"CB7_B"
$PN"236"40;
"ALERT_N \B"
$PN"62"34;
"CA0_A"
$PN"66"76;
"CA0_B"
$PN"76"177;
"CA1_A"
$PN"211"176;
"CA1_B"
$PN"221"106;
"CA2_A"
$PN"68"175;
"CA2_B"
$PN"78"174;
"CA3_A"
$PN"213"173;
"CA3_B"
$PN"223"172;
"CA4_A"
$PN"70"108;
"CA4_B"
$PN"80"107;
"CA5_A"
$PN"215"105;
"CA5_B"
$PN"225"78;
"CA6_A"
$PN"72"75;
"CA6_B"
$PN"82"171;
"CB6_A"
$PN"203"170;
"CB5_A"
$PN"60"169;
"CB3_A"
$PN"198"44;
"CB2_A"
$PN"196"43;
"CB0_A"
$PN"51"41;
"CB6_B"
$PN"234"39;
"CB5_B"
$PN"91"168;
"CB4_B"
$PN"89"167;
"CB3_B"
$PN"243"166;
"CB2_B"
$PN"241"165;
"CB1_B"
$PN"98"32;
"CB0_B"
$PN"96"164;
"CK_C \B"
$PN"218"163;
"CK_T"
$PN"217"162;
"CS0_A_N"
$PN"64"37;
"CS0_B_N"
$PN"84"73;
"CS1_A_N"
$PN"209"74;
"CS1_B_N"
$PN"229"161;
"DQ30_A"
$PN"192"81;
"DQ29_A"
$PN"49"59;
"DQ28_A"
$PN"47"58;
"DQ27_A"
$PN"187"57;
"DQ26_A"
$PN"185"56;
"DQ25_A"
$PN"42"55;
"DQ24_A"
$PN"40"54;
"DQ23_A"
$PN"183"160;
"DQ22_A"
$PN"181"159;
"DQ21_A"
$PN"38"158;
"DQ20_A"
$PN"36"53;
"DQ19_A"
$PN"176"157;
"DQ18_A"
$PN"174"156;
"DQ17_A"
$PN"31"155;
"DQ16_A"
$PN"29"72;
"DQ15_A"
$PN"172"52;
"DQ14_A"
$PN"170"51;
"DQ13_A"
$PN"27"154;
"DQ12_A"
$PN"25"153;
"DQ11_A"
$PN"165"152;
"DQ10_A"
$PN"163"151;
"DQ9_A"
$PN"20"150;
"DQ8_A"
$PN"18"149;
"DQ7_A"
$PN"161"148;
"DQ6_A"
$PN"159"147;
"DQ5_A"
$PN"16"146;
"DQ4_A"
$PN"14"145;
"DQ3_A"
$PN"154"144;
"DQ2_A"
$PN"152"143;
"DQ1_A"
$PN"9"142;
"DQ0_A"
$PN"7"141;
"DQ31_B"
$PN"287"140;
"DQ30_B"
$PN"285"139;
"DQ29_B"
$PN"142"138;
"DQ28_B"
$PN"140"137;
"DQ27_B"
$PN"280"136;
"DQ26_B"
$PN"278"135;
"DQ25_B"
$PN"135"134;
"DQ24_B"
$PN"133"133;
"DQ23_B"
$PN"276"132;
"DQ22_B"
$PN"274"131;
"DQ21_B"
$PN"131"130;
"DQ20_B"
$PN"129"129;
"DQ19_B"
$PN"269"128;
"DQ18_B"
$PN"267"127;
"DQ17_B"
$PN"124"126;
"DQ16_B"
$PN"122"125;
"DQ15_B"
$PN"265"124;
"DQ14_B"
$PN"263"123;
"DQ13_B"
$PN"120"122;
"DQ12_B"
$PN"118"121;
"DQ11_B"
$PN"258"120;
"DQ10_B"
$PN"256"119;
"DQ9_B"
$PN"113"118;
"DQ8_B"
$PN"111"117;
"DQ7_B"
$PN"254"116;
"DQ6_B"
$PN"252"115;
"DQ5_B"
$PN"109"114;
"DQ4_B"
$PN"107"113;
"DQ3_B"
$PN"247"112;
"DQ2_B"
$PN"245"111;
"DQ1_B"
$PN"102"110;
"DQ0_B"
$PN"100"71;
"HAS"
$PN"148"33;
"HSCL"
$PN"4"27;
"HSDA"
$PN"5"25;
"LBD||RSP_A_N"
$PN"86"28;
"LBS||RSP_B_N"
$PN"87"30;
"PAR_A"
$PN"74"109;
"PAR_B"
$PN"227"38;
"RESET_N \B"
$PN"207"35;
"RFU6"
$PN"232"17;
"RFU5"
$PN"231"16;
"RFU4"
$PN"220"15;
"RFU3"
$PN"150"31;
"RFU2"
$PN"149"26;
"RFU1"
$PN"144"46;
"RFU0"
$PN"2"29;
"VIN_MGMT"
$PN"3"20;
%"SCONN288_DDR506112002KQ"
"2","(-4600,4375)","0","pure_quanta","I537";
;
LOCATION"J1"
$SEC"2"
CDS_SEC"2"
MATERIAL"IO"
PART_TYPE"SMLF"
VALUE"SCONN288_DDR506112002KQ"
PART_NUMBER"DFHST8FS479"
NEEDS_NO_SIZE"TRUE"
CDS_LMAN_SYM_OUTLINE"-600,1150,600,-1150"
CDS_LIB"pure_quanta";
"DQS7_A_C||TDQS7_A_C \B"
$PN"178"50;
"DQS6_A_T||TDQS6_A_T"
$PN"168"49;
"DQS8_B_T||TDQS8_B_T"
$PN"283"62;
"DQS8_B_C||TDQS8_B_C \B"
$PN"282"63;
"DQS7_B_T||TDQS7_B_T"
$PN"272"64;
"DQS0_A_C \B"
$PN"12"60;
"DQS0_A_T"
$PN"11"104;
"DQS0_B_C \B"
$PN"105"103;
"DQS0_B_T"
$PN"104"102;
"DQS1_A_C \B"
$PN"23"101;
"DQS1_A_T"
$PN"22"100;
"DQS1_B_C \B"
$PN"116"99;
"DQS1_B_T"
$PN"115"98;
"DQS2_A_C \B"
$PN"34"97;
"DQS2_A_T"
$PN"33"96;
"DQS2_B_C \B"
$PN"127"95;
"DQS2_B_T"
$PN"126"94;
"DQS3_A_C \B"
$PN"45"93;
"DQS3_A_T"
$PN"44"92;
"DQS3_B_C \B"
$PN"138"91;
"DQS3_B_T"
$PN"137"90;
"DQS4_A_C \B"
$PN"56"89;
"DQS4_A_T"
$PN"55"88;
"DQS4_B_C \B"
$PN"238"70;
"DQS4_B_T"
$PN"239"69;
"DQS5_A_C||TDQS5_A_C||DQS5_A_T||TDQS5_A_T \B"
$PN"156"87;
"DQS5_A_T||TDQS5_A_T"
$PN"157"86;
"DQS5_B_C||TDQS5_B_C \B"
$PN"249"68;
"DQS5_B_T||TDQS5_B_T"
$PN"250"85;
"DQS6_A_C||TDQS6_A_C||DQS6_A_T||TDQS6_A_T \B"
$PN"167"48;
"DQS6_B_C||TDQS6_B_C \B"
$PN"260"67;
"DQS6_B_T||TDQS6_B_T"
$PN"261"66;
"DQS7_A_T||TDQS7_A_T"
$PN"179"84;
"DQS7_B_C||TDQS7_B_C \B"
$PN"271"65;
"DQS8_A_C||TDQS8_A_C \B"
$PN"189"83;
"DQS8_A_T||TDQS8_A_T"
$PN"190"82;
"DQS9_A_C||TDQS9_A_C \B"
$PN"200"80;
"DQS9_A_T||TDQS9_A_T"
$PN"201"79;
"DQS9_B_C||TDQS9_B_C \B"
$PN"94"61;
"DQS9_B_T||TDQS9_B_T||DBI4_B_N"
$PN"93"47;
%"SCONN288_DDR506112002KQ"
"3","(-1450,3700)","0","pure_quanta","I538";
;
LOCATION"J1"
$SEC"3"
CDS_SEC"3"
PART_TYPE"SMLF"
MATERIAL"IO"
PART_NUMBER"DFHST8FS479"
VALUE"SCONN288_DDR506112002KQ"
NEEDS_NO_SIZE"TRUE"
CDS_LMAN_SYM_OUTLINE"-450,1800,450,-1750"
CDS_LIB"pure_quanta";
"G3"
$PN"G3"21;
"G2"
$PN"G2"21;
"G1"
$PN"G1"21;
"VSS62"
$PN"141"21;
"VSS61"
$PN"139"21;
"VSS60"
$PN"136"21;
"VSS58"
$PN"132"21;
"VSS104"
$PN"240"22;
"VSS102"
$PN"235"22;
"VSS100"
$PN"230"22;
"VIN_BULK2"
$PN"146"24;
"VIN_BULK1"
$PN"145"24;
"VIN_BULK0"
$PN"1"24;
"VSS126"
$PN"288"22;
"VSS125"
$PN"286"22;
"VSS124"
$PN"284"22;
"VSS123"
$PN"281"22;
"VSS122"
$PN"279"22;
"VSS121"
$PN"277"22;
"VSS120"
$PN"275"22;
"VSS119"
$PN"273"22;
"VSS118"
$PN"270"22;
"VSS117"
$PN"268"22;
"VSS116"
$PN"266"22;
"VSS115"
$PN"264"22;
"VSS114"
$PN"262"22;
"VSS113"
$PN"259"22;
"VSS112"
$PN"257"22;
"VSS111"
$PN"255"22;
"VSS110"
$PN"253"22;
"VSS109"
$PN"251"22;
"VSS108"
$PN"248"22;
"VSS107"
$PN"246"22;
"VSS106"
$PN"244"22;
"VSS105"
$PN"242"22;
"VSS103"
$PN"237"22;
"VSS101"
$PN"233"22;
"VSS99"
$PN"228"22;
"VSS98"
$PN"226"22;
"VSS97"
$PN"224"22;
"VSS96"
$PN"222"22;
"VSS95"
$PN"219"22;
"VSS94"
$PN"216"22;
"VSS93"
$PN"214"22;
"VSS92"
$PN"212"22;
"VSS91"
$PN"210"22;
"VSS90"
$PN"208"22;
"VSS89"
$PN"206"22;
"VSS88"
$PN"204"22;
"VSS87"
$PN"202"22;
"VSS86"
$PN"199"22;
"VSS85"
$PN"197"22;
"VSS84"
$PN"195"22;
"VSS83"
$PN"193"22;
"VSS82"
$PN"191"22;
"VSS81"
$PN"188"22;
"VSS80"
$PN"186"22;
"VSS79"
$PN"184"22;
"VSS78"
$PN"182"22;
"VSS77"
$PN"180"22;
"VSS76"
$PN"177"22;
"VSS75"
$PN"175"22;
"VSS74"
$PN"173"22;
"VSS73"
$PN"171"22;
"VSS72"
$PN"169"22;
"VSS71"
$PN"166"22;
"VSS70"
$PN"164"22;
"VSS69"
$PN"162"22;
"VSS68"
$PN"160"22;
"VSS67"
$PN"158"22;
"VSS66"
$PN"155"22;
"VSS65"
$PN"153"22;
"VSS64"
$PN"151"22;
"VSS63"
$PN"143"21;
"VSS59"
$PN"134"21;
"VSS57"
$PN"130"21;
"VSS56"
$PN"128"21;
"VSS55"
$PN"125"21;
"VSS54"
$PN"123"21;
"VSS53"
$PN"121"21;
"VSS52"
$PN"119"21;
"VSS51"
$PN"117"21;
"VSS50"
$PN"114"21;
"VSS49"
$PN"112"21;
"VSS48"
$PN"110"21;
"VSS47"
$PN"108"21;
"VSS46"
$PN"106"21;
"VSS45"
$PN"103"21;
"VSS44"
$PN"101"21;
"VSS43"
$PN"99"21;
"VSS42"
$PN"97"21;
"VSS41"
$PN"95"21;
"VSS40"
$PN"92"21;
"VSS39"
$PN"90"21;
"VSS38"
$PN"88"21;
"VSS37"
$PN"85"21;
"VSS36"
$PN"83"21;
"VSS35"
$PN"81"21;
"VSS34"
$PN"79"21;
"VSS33"
$PN"77"21;
"VSS32"
$PN"75"21;
"VSS31"
$PN"73"21;
"VSS30"
$PN"71"21;
"VSS29"
$PN"69"21;
"VSS28"
$PN"67"21;
"VSS27"
$PN"65"21;
"VSS26"
$PN"63"21;
"VSS25"
$PN"61"21;
"VSS24"
$PN"59"21;
"VSS23"
$PN"57"21;
"VSS22"
$PN"54"21;
"VSS21"
$PN"52"21;
"VSS20"
$PN"50"21;
"VSS19"
$PN"48"21;
"VSS18"
$PN"46"21;
"VSS17"
$PN"43"21;
"VSS16"
$PN"41"21;
"VSS15"
$PN"39"21;
"VSS14"
$PN"37"21;
"VSS13"
$PN"35"21;
"VSS12"
$PN"32"21;
"VSS11"
$PN"30"21;
"VSS10"
$PN"28"21;
"VSS9"
$PN"26"21;
"VSS8"
$PN"24"21;
"VSS7"
$PN"21"21;
"VSS6"
$PN"19"21;
"VSS5"
$PN"17"21;
"VSS4"
$PN"15"21;
"VSS3"
$PN"13"21;
"VSS2"
$PN"10"21;
"VSS1"
$PN"8"21;
"VSS0"
$PN"6"21;
%"Q_RES"
"1","(-7800,2725)","0","pure_quanta","I539";
;
$LOCATION"R1568"
CDS_LOCATION"R1568"
$SEC"1"
CDS_SEC"1"
VALUE"49.9"
PART_NUMBER"CS04992FB07"
TOLERANCE"1%"
WATTAGE"1/16W"
PACK_TYPE"0402LF"
MATERIAL"CHIP"
CDS_LIB"pure_quanta";
"B"
$PN"2"27;
"A"
$PN"1"19;
END.
